(kicad_pcb
	(version 20260206)
	(generator "pcbnew")
	(generator_version "10.0")
	(general
		(thickness 1.6)
		(legacy_teardrops no)
	)
	(paper "A4")
	(title_block
		(title "Wiwynn_Tioga_Pass_MB.brd")
		(comment 1 "Tioga Pass / footprints 4694-4701 of 4770")
	)
	(layers
		(0 "F.Cu" signal "TOP")
		(4 "In1.Cu" signal "L2GND")
		(6 "In2.Cu" signal "L3")
		(8 "In3.Cu" signal "L4GND")
		(10 "In4.Cu" signal "L5")
		(12 "In5.Cu" signal "L6GND")
		(14 "In6.Cu" signal "L7VCC")
		(16 "In7.Cu" signal "L8VCC")
		(18 "In8.Cu" signal "L9GND")
		(20 "In9.Cu" signal "L10")
		(22 "In10.Cu" signal "L11GND")
		(24 "In11.Cu" signal "L12")
		(26 "In12.Cu" signal "L13GND")
		(2 "B.Cu" signal "BOTTOM")
		(9 "F.Adhes" user "F.Adhesive")
		(11 "B.Adhes" user "B.Adhesive")
		(13 "F.Paste" user "Package Geometry/Pastemask Top")
		(15 "B.Paste" user "Package Geometry/Pastemask Bottom")
		(5 "F.SilkS" user "Ref Des/Silkscreen Top")
		(7 "B.SilkS" user "Ref Des/Silkscreen Bottom")
		(1 "F.Mask" user "Board Geometry/Soldermask Top")
		(3 "B.Mask" user "Board Geometry/Soldermask Bottom")
		(17 "Dwgs.User" user "User.Drawings")
		(19 "Cmts.User" user "User.Comments")
		(21 "Eco1.User" user "User.Eco1")
		(23 "Eco2.User" user "User.Eco2")
		(25 "Edge.Cuts" user "Board Geometry/Outline")
		(27 "Margin" user)
		(31 "F.CrtYd" user "Package Geometry/Place Bound Top")
		(29 "B.CrtYd" user "Package Geometry/Place Bound Bottom")
		(35 "F.Fab" user "Ref Des/Assembly Top")
		(33 "B.Fab" user "Ref Des/Assembly Bottom")
	)
	(footprint ""
		(layer "B.Cu")
		(at 174.809404 -4.57581 -90)
		(property "Reference" "R6U6"
			(at 0 0 90)
			(layer "B.SilkS")
			(hide yes)
			(effects
				(font
					(size 1.27 1.27)
				)
				(justify mirror)
			)
		)
		(property "Value" ""
			(at 0 0 90)
			(layer "B.Fab")
			(effects
				(font
					(size 1.27 1.27)
				)
				(justify mirror)
			)
		)
		(duplicate_pad_numbers_are_jumpers no)
		(fp_rect
			(start 0.2794 0.9906)
			(end -0.2794 -0.1016)
			(stroke
				(width 0)
				(type default)
			)
			(fill no)
			(layer "B.CrtYd")
		)
		(fp_line
			(start -0.2794 0.9906)
			(end -0.2794 -0.1016)
			(stroke
				(width 0.1)
				(type default)
			)
			(layer "B.Fab")
		)
		(fp_line
			(start 0.2794 0.9906)
			(end -0.2794 0.9906)
			(stroke
				(width 0.1)
				(type default)
			)
			(layer "B.Fab")
		)
		(fp_line
			(start -0.2794 -0.1016)
			(end 0.2794 -0.1016)
			(stroke
				(width 0.1)
				(type default)
			)
			(layer "B.Fab")
		)
		(fp_line
			(start 0.2794 -0.1016)
			(end 0.2794 0.9906)
			(stroke
				(width 0.1)
				(type default)
			)
			(layer "B.Fab")
		)
		(pad "1" smd rect
			(at 0 0 90)
			(size 0.508 0.508)
			(layers "B.Cu" "B.Mask" "B.Paste")
			(net "PVDDQ_GHJ")
		)
		(pad "2" smd rect
			(at 0 0.889 90)
			(size 0.508 0.508)
			(layers "B.Cu" "B.Mask" "B.Paste")
			(net "VSENSE_PVDDQ_GHJ_VTT")
		)
		(zone
			(layer "B.Cu")
			(hatch none 0.5)
			(connect_pads
				(clearance 0)
			)
			(min_thickness 0.25)
			(keepout
				(tracks allowed)
				(vias not_allowed)
				(pads allowed)
				(copperpour not_allowed)
				(footprints allowed)
			)
			(placement
				(enabled no)
				(sheetname "")
			)
			(fill
				(thermal_gap 0.5)
				(thermal_bridge_width 0.5)
				(island_removal_mode 0)
			)
			(polygon
				(pts
					(xy 174.174404 -4.32181) (xy 174.555404 -4.32181) (xy 174.555404 -4.82981) (xy 174.174404 -4.82981)
				)
			)
		)
		(zone
			(layer "B.Cu")
			(hatch none 0.5)
			(connect_pads
				(clearance 0)
			)
			(min_thickness 0.25)
			(keepout
				(tracks not_allowed)
				(vias allowed)
				(pads allowed)
				(copperpour not_allowed)
				(footprints allowed)
			)
			(placement
				(enabled no)
				(sheetname "")
			)
			(fill
				(thermal_gap 0.5)
				(thermal_bridge_width 0.5)
				(island_removal_mode 0)
			)
			(polygon
				(pts
					(xy 174.174404 -4.32181) (xy 174.555404 -4.32181) (xy 174.555404 -4.82981) (xy 174.174404 -4.82981)
				)
			)
		)
	)
	(footprint ""
		(layer "B.Cu")
		(at 269.521686 -73.51014)
		(property "Reference" "C5P31"
			(at 0 0 0)
			(layer "B.SilkS")
			(hide yes)
			(effects
				(font
					(size 1.27 1.27)
				)
				(justify mirror)
			)
		)
		(property "Value" ""
			(at 0 0 0)
			(layer "B.Fab")
			(effects
				(font
					(size 1.27 1.27)
				)
				(justify mirror)
			)
		)
		(duplicate_pad_numbers_are_jumpers no)
		(fp_poly
			(pts
				(xy 0.7239 -0.2159) (xy -0.7239 -0.2159) (xy -0.7239 1.9939) (xy 0.7239 1.9939)
			)
			(stroke
				(width 0)
				(type default)
			)
			(fill no)
			(layer "B.CrtYd")
		)
		(fp_line
			(start -0.7239 -0.2159)
			(end 0.7239 -0.2159)
			(stroke
				(width 0.1)
				(type default)
			)
			(layer "B.Fab")
		)
		(fp_line
			(start -0.7239 1.9939)
			(end -0.7239 -0.2159)
			(stroke
				(width 0.1)
				(type default)
			)
			(layer "B.Fab")
		)
		(fp_line
			(start 0.7239 -0.2159)
			(end 0.7239 1.9939)
			(stroke
				(width 0.1)
				(type default)
			)
			(layer "B.Fab")
		)
		(fp_line
			(start 0.7239 1.9939)
			(end -0.7239 1.9939)
			(stroke
				(width 0.1)
				(type default)
			)
			(layer "B.Fab")
		)
		(pad "1" smd rect
			(at 0 0 180)
			(size 1.27 1.016)
			(layers "B.Cu" "B.Mask" "B.Paste")
			(net "PVCCMCP_CPU0")
		)
		(pad "2" smd rect
			(at 0 1.778 180)
			(size 1.27 1.016)
			(layers "B.Cu" "B.Mask" "B.Paste")
			(net "GND")
		)
		(zone
			(layer "B.Cu")
			(hatch none 0.5)
			(connect_pads
				(clearance 0)
			)
			(min_thickness 0.25)
			(keepout
				(tracks not_allowed)
				(vias allowed)
				(pads allowed)
				(copperpour not_allowed)
				(footprints allowed)
			)
			(placement
				(enabled no)
				(sheetname "")
			)
			(fill
				(thermal_gap 0.5)
				(thermal_bridge_width 0.5)
				(island_removal_mode 0)
			)
			(polygon
				(pts
					(xy 270.156686 -73.00214) (xy 268.886686 -73.00214) (xy 268.886686 -72.24014) (xy 270.156686 -72.24014)
				)
			)
		)
	)
	(footprint ""
		(layer "B.Cu")
		(at 95.400368 3.4798 90)
		(property "Reference" "SH8U1"
			(at 0 0 90)
			(layer "B.SilkS")
			(hide yes)
			(effects
				(font
					(size 1.27 1.27)
				)
				(justify mirror)
			)
		)
		(property "Value" ""
			(at 0 0 90)
			(layer "B.Fab")
			(effects
				(font
					(size 1.27 1.27)
				)
				(justify mirror)
			)
		)
		(duplicate_pad_numbers_are_jumpers no)
		(fp_poly
			(pts
				(xy 0.1651 -0.0508) (xy 0.1651 0.5842) (xy -0.1651 0.5842) (xy -0.1651 -0.0508)
			)
			(stroke
				(width 0)
				(type default)
			)
			(fill no)
			(layer "B.CrtYd")
		)
		(fp_line
			(start 0.1651 -0.0508)
			(end -0.1651 -0.0508)
			(stroke
				(width 0.1)
				(type default)
			)
			(layer "B.Fab")
		)
		(fp_line
			(start -0.1651 -0.0508)
			(end -0.1651 0.5842)
			(stroke
				(width 0.1)
				(type default)
			)
			(layer "B.Fab")
		)
		(fp_line
			(start 0.1651 0.5842)
			(end 0.1651 -0.0508)
			(stroke
				(width 0.1)
				(type default)
			)
			(layer "B.Fab")
		)
		(fp_line
			(start -0.1651 0.5842)
			(end 0.1651 0.5842)
			(stroke
				(width 0.1)
				(type default)
			)
			(layer "B.Fab")
		)
		(pad "1" smd custom
			(at 0 0 90)
			(size 0.0762 0.0762)
			(layers "B.Cu" "B.Mask" "B.Paste")
			(net "VR_PVTT_GHJ_SNS")
			(options
				(clearance outline)
				(anchor circle)
			)
			(primitives
				(gr_poly
					(pts
						(arc
							(start -0.1524 0.10795)
							(mid -0.098518 0.130268)
							(end -0.0762 0.18415)
						)
						(xy -0.0762 0.22225) (xy 0.0762 0.22225)
						(arc
							(start 0.0762 0.18415)
							(mid 0.098518 0.130268)
							(end 0.1524 0.10795)
						)
						(xy 0.1524 -0.22225) (xy -0.1524 -0.22225)
					)
					(width 0)
					(fill yes)
				)
			)
		)
		(pad "2" smd custom
			(at 0 0.5334 270)
			(size 0.0762 0.0762)
			(layers "B.Cu" "B.Mask" "B.Paste")
			(net "PVTT_GHJ")
			(options
				(clearance outline)
				(anchor circle)
			)
			(primitives
				(gr_poly
					(pts
						(arc
							(start -0.1524 0.10795)
							(mid -0.098518 0.130268)
							(end -0.0762 0.18415)
						)
						(xy -0.0762 0.22225) (xy 0.0762 0.22225)
						(arc
							(start 0.0762 0.18415)
							(mid 0.098518 0.130268)
							(end 0.1524 0.10795)
						)
						(xy 0.1524 -0.22225) (xy -0.1524 -0.22225)
					)
					(width 0)
					(fill yes)
				)
			)
		)
	)
	(footprint ""
		(layer "B.Cu")
		(at 137.033 -121.412)
		(property "Reference" ""
			(at 0 0 0)
			(layer "B.SilkS")
			(hide yes)
			(effects
				(font
					(size 1.27 1.27)
				)
				(justify mirror)
			)
		)
		(property "Value" ""
			(at 0 0 0)
			(layer "B.Fab")
			(effects
				(font
					(size 1.27 1.27)
				)
				(justify mirror)
			)
		)
		(duplicate_pad_numbers_are_jumpers no)
		(fp_poly
			(pts
				(arc
					(start 2.032 0)
					(mid -2.032 0)
					(end 2.032 0)
				)
			)
			(stroke
				(width 0)
				(type default)
			)
			(fill no)
			(layer "B.CrtYd")
		)
		(pad "1" smd circle
			(at 0 0 180)
			(size 1.016 1.016)
			(layers "B.Cu" "B.Mask" "B.Paste")
			(net "Net_390")
		)
		(zone
			(layers "F.Cu" "B.Cu" "In1.Cu" "In2.Cu" "In3.Cu" "In4.Cu" "In5.Cu" "In6.Cu"
				"In7.Cu" "In8.Cu" "In9.Cu" "In10.Cu" "In11.Cu" "In12.Cu"
			)
			(hatch none 0.5)
			(connect_pads
				(clearance 0)
			)
			(min_thickness 0.25)
			(keepout
				(tracks allowed)
				(vias not_allowed)
				(pads allowed)
				(copperpour not_allowed)
				(footprints allowed)
			)
			(placement
				(enabled no)
				(sheetname "")
			)
			(fill
				(thermal_gap 0.5)
				(thermal_bridge_width 0.5)
				(island_removal_mode 0)
			)
			(polygon
				(pts
					(arc
						(start 138.557 -121.412)
						(mid 135.509 -121.412)
						(end 138.557 -121.412)
					)
				)
			)
		)
		(zone
			(layer "B.Cu")
			(hatch none 0.5)
			(connect_pads
				(clearance 0)
			)
			(min_thickness 0.25)
			(keepout
				(tracks not_allowed)
				(vias allowed)
				(pads allowed)
				(copperpour not_allowed)
				(footprints allowed)
			)
			(placement
				(enabled no)
				(sheetname "")
			)
			(fill
				(thermal_gap 0.5)
				(thermal_bridge_width 0.5)
				(island_removal_mode 0)
			)
			(polygon
				(pts
					(arc
						(start 138.557 -121.412)
						(mid 135.509 -121.412)
						(end 138.557 -121.412)
					)
				)
			)
		)
	)
	(footprint ""
		(layer "B.Cu")
		(at 275.008086 -77.82814)
		(property "Reference" "C5P18"
			(at 0 0 0)
			(layer "B.SilkS")
			(hide yes)
			(effects
				(font
					(size 1.27 1.27)
				)
				(justify mirror)
			)
		)
		(property "Value" ""
			(at 0 0 0)
			(layer "B.Fab")
			(effects
				(font
					(size 1.27 1.27)
				)
				(justify mirror)
			)
		)
		(duplicate_pad_numbers_are_jumpers no)
		(fp_poly
			(pts
				(xy 0.7239 -0.2159) (xy -0.7239 -0.2159) (xy -0.7239 1.9939) (xy 0.7239 1.9939)
			)
			(stroke
				(width 0)
				(type default)
			)
			(fill no)
			(layer "B.CrtYd")
		)
		(fp_line
			(start -0.7239 -0.2159)
			(end 0.7239 -0.2159)
			(stroke
				(width 0.1)
				(type default)
			)
			(layer "B.Fab")
		)
		(fp_line
			(start -0.7239 1.9939)
			(end -0.7239 -0.2159)
			(stroke
				(width 0.1)
				(type default)
			)
			(layer "B.Fab")
		)
		(fp_line
			(start 0.7239 -0.2159)
			(end 0.7239 1.9939)
			(stroke
				(width 0.1)
				(type default)
			)
			(layer "B.Fab")
		)
		(fp_line
			(start 0.7239 1.9939)
			(end -0.7239 1.9939)
			(stroke
				(width 0.1)
				(type default)
			)
			(layer "B.Fab")
		)
		(pad "1" smd rect
			(at 0 0 180)
			(size 1.27 1.016)
			(layers "B.Cu" "B.Mask" "B.Paste")
			(net "PVCCMCP_CPU0")
		)
		(pad "2" smd rect
			(at 0 1.778 180)
			(size 1.27 1.016)
			(layers "B.Cu" "B.Mask" "B.Paste")
			(net "GND")
		)
		(zone
			(layer "B.Cu")
			(hatch none 0.5)
			(connect_pads
				(clearance 0)
			)
			(min_thickness 0.25)
			(keepout
				(tracks not_allowed)
				(vias allowed)
				(pads allowed)
				(copperpour not_allowed)
				(footprints allowed)
			)
			(placement
				(enabled no)
				(sheetname "")
			)
			(fill
				(thermal_gap 0.5)
				(thermal_bridge_width 0.5)
				(island_removal_mode 0)
			)
			(polygon
				(pts
					(xy 275.643086 -77.32014) (xy 274.373086 -77.32014) (xy 274.373086 -76.55814) (xy 275.643086 -76.55814)
				)
			)
		)
	)
	(footprint ""
		(layer "B.Cu")
		(at 214.503 -70.358)
		(property "Reference" "C6P21"
			(at 0 0 0)
			(layer "B.SilkS")
			(hide yes)
			(effects
				(font
					(size 1.27 1.27)
				)
				(justify mirror)
			)
		)
		(property "Value" ""
			(at 0 0 0)
			(layer "B.Fab")
			(effects
				(font
					(size 1.27 1.27)
				)
				(justify mirror)
			)
		)
		(duplicate_pad_numbers_are_jumpers no)
		(fp_poly
			(pts
				(xy 0.4953 -0.2032) (xy -0.4953 -0.2032) (xy -0.4953 1.6002) (xy 0.4953 1.6002)
			)
			(stroke
				(width 0)
				(type default)
			)
			(fill no)
			(layer "B.CrtYd")
		)
		(fp_line
			(start -0.4953 -0.2032)
			(end -0.4953 1.6002)
			(stroke
				(width 0.1)
				(type default)
			)
			(layer "B.Fab")
		)
		(fp_line
			(start -0.4953 1.6002)
			(end 0.4953 1.6002)
			(stroke
				(width 0.1)
				(type default)
			)
			(layer "B.Fab")
		)
		(fp_line
			(start 0.4953 -0.2032)
			(end -0.4953 -0.2032)
			(stroke
				(width 0.1)
				(type default)
			)
			(layer "B.Fab")
		)
		(fp_line
			(start 0.4953 1.6002)
			(end 0.4953 -0.2032)
			(stroke
				(width 0.1)
				(type default)
			)
			(layer "B.Fab")
		)
		(pad "1" smd rect
			(at 0 0 180)
			(size 0.762 0.889)
			(layers "B.Cu" "B.Mask" "B.Paste")
			(net "PVCCIN_CPU0")
		)
		(pad "2" smd rect
			(at 0 1.397 180)
			(size 0.762 0.889)
			(layers "B.Cu" "B.Mask" "B.Paste")
			(net "GND")
		)
		(zone
			(layer "B.Cu")
			(hatch none 0.5)
			(connect_pads
				(clearance 0)
			)
			(min_thickness 0.25)
			(keepout
				(tracks not_allowed)
				(vias allowed)
				(pads allowed)
				(copperpour not_allowed)
				(footprints allowed)
			)
			(placement
				(enabled no)
				(sheetname "")
			)
			(fill
				(thermal_gap 0.5)
				(thermal_bridge_width 0.5)
				(island_removal_mode 0)
			)
			(polygon
				(pts
					(xy 214.884 -69.9135) (xy 214.122 -69.9135) (xy 214.122 -69.4055) (xy 214.884 -69.4055)
				)
			)
		)
	)
	(footprint ""
		(layer "B.Cu")
		(at 197.848728 -72.855582 90)
		(property "Reference" "C6P20"
			(at 0 0 90)
			(layer "B.SilkS")
			(hide yes)
			(effects
				(font
					(size 1.27 1.27)
				)
				(justify mirror)
			)
		)
		(property "Value" ""
			(at 0 0 90)
			(layer "B.Fab")
			(effects
				(font
					(size 1.27 1.27)
				)
				(justify mirror)
			)
		)
		(duplicate_pad_numbers_are_jumpers no)
		(fp_rect
			(start -0.7239 -0.2159)
			(end 0.7239 1.9939)
			(stroke
				(width 0)
				(type default)
			)
			(fill no)
			(layer "B.CrtYd")
		)
		(fp_line
			(start 0.7239 -0.2159)
			(end 0.7239 1.9939)
			(stroke
				(width 0.1)
				(type default)
			)
			(layer "B.Fab")
		)
		(fp_line
			(start -0.7239 -0.2159)
			(end 0.7239 -0.2159)
			(stroke
				(width 0.1)
				(type default)
			)
			(layer "B.Fab")
		)
		(fp_line
			(start 0.7239 1.9939)
			(end -0.7239 1.9939)
			(stroke
				(width 0.1)
				(type default)
			)
			(layer "B.Fab")
		)
		(fp_line
			(start -0.7239 1.9939)
			(end -0.7239 -0.2159)
			(stroke
				(width 0.1)
				(type default)
			)
			(layer "B.Fab")
		)
		(pad "1" smd rect
			(at 0 0 270)
			(size 1.27 1.016)
			(layers "B.Cu" "B.Mask" "B.Paste")
			(net "VR_FET_SW_P12V_STBY_PVCCIN_CPU0")
		)
		(pad "2" smd rect
			(at 0 1.778 270)
			(size 1.27 1.016)
			(layers "B.Cu" "B.Mask" "B.Paste")
			(net "GND")
		)
		(zone
			(layer "B.Cu")
			(hatch none 0.5)
			(connect_pads
				(clearance 0)
			)
			(min_thickness 0.25)
			(keepout
				(tracks not_allowed)
				(vias allowed)
				(pads allowed)
				(copperpour not_allowed)
				(footprints allowed)
			)
			(placement
				(enabled no)
				(sheetname "")
			)
			(fill
				(thermal_gap 0.5)
				(thermal_bridge_width 0.5)
				(island_removal_mode 0)
			)
			(polygon
				(pts
					(xy 198.356728 -72.220582) (xy 199.118728 -72.220582) (xy 199.118728 -73.490582) (xy 198.356728 -73.490582)
				)
			)
		)
	)
	(footprint ""
		(layer "B.Cu")
		(at 13.716 -54.889908 90)
		(property "Reference" "C1E15"
			(at 0 0 90)
			(layer "B.SilkS")
			(hide yes)
			(effects
				(font
					(size 1.27 1.27)
				)
				(justify mirror)
			)
		)
		(property "Value" ""
			(at 0 0 90)
			(layer "B.Fab")
			(effects
				(font
					(size 1.27 1.27)
				)
				(justify mirror)
			)
		)
		(duplicate_pad_numbers_are_jumpers no)
		(fp_rect
			(start -0.7239 -0.2159)
			(end 0.7239 1.9939)
			(stroke
				(width 0)
				(type default)
			)
			(fill no)
			(layer "B.CrtYd")
		)
		(fp_line
			(start 0.7239 -0.2159)
			(end 0.7239 1.9939)
			(stroke
				(width 0.1)
				(type default)
			)
			(layer "B.Fab")
		)
		(fp_line
			(start -0.7239 -0.2159)
			(end 0.7239 -0.2159)
			(stroke
				(width 0.1)
				(type default)
			)
			(layer "B.Fab")
		)
		(fp_line
			(start 0.7239 1.9939)
			(end -0.7239 1.9939)
			(stroke
				(width 0.1)
				(type default)
			)
			(layer "B.Fab")
		)
		(fp_line
			(start -0.7239 1.9939)
			(end -0.7239 -0.2159)
			(stroke
				(width 0.1)
				(type default)
			)
			(layer "B.Fab")
		)
		(pad "1" smd rect
			(at 0 0 270)
			(size 1.27 1.016)
			(layers "B.Cu" "B.Mask" "B.Paste")
			(net "P12V_PSU")
		)
		(pad "2" smd rect
			(at 0 1.778 270)
			(size 1.27 1.016)
			(layers "B.Cu" "B.Mask" "B.Paste")
			(net "GND")
		)
		(zone
			(layer "B.Cu")
			(hatch none 0.5)
			(connect_pads
				(clearance 0)
			)
			(min_thickness 0.25)
			(keepout
				(tracks not_allowed)
				(vias allowed)
				(pads allowed)
				(copperpour not_allowed)
				(footprints allowed)
			)
			(placement
				(enabled no)
				(sheetname "")
			)
			(fill
				(thermal_gap 0.5)
				(thermal_bridge_width 0.5)
				(island_removal_mode 0)
			)
			(polygon
				(pts
					(xy 14.224 -54.254908) (xy 14.986 -54.254908) (xy 14.986 -55.524908) (xy 14.224 -55.524908)
				)
			)
		)
	)
)
